(kicad_pcb
	(version 20260206)
	(generator "pcbnew")
	(generator_version "10.0")
	(general
		(thickness 1.6)
		(legacy_teardrops no)
	)
	(paper "A4")
	(title_block
		(title "03242023_DA0F0TMBIJ0_F0T_Motherboard_J_brd_V01_OCP.brd")
		(comment 1 "Grand Teton / footprints 1131-1135 of 6105")
	)
	(layers
		(0 "F.Cu" signal "TOP")
		(4 "In1.Cu" signal "GND")
		(6 "In2.Cu" signal "IN1")
		(8 "In3.Cu" signal "GND1")
		(10 "In4.Cu" signal "IN2")
		(12 "In5.Cu" signal "GND2")
		(14 "In6.Cu" signal "IN3")
		(16 "In7.Cu" signal "GND3")
		(18 "In8.Cu" signal "VCC")
		(20 "In9.Cu" signal "VCC1")
		(22 "In10.Cu" signal "GND4")
		(24 "In11.Cu" signal "IN4")
		(26 "In12.Cu" signal "GND5")
		(28 "In13.Cu" signal "IN5")
		(30 "In14.Cu" signal "GND6")
		(32 "In15.Cu" signal "IN6")
		(34 "In16.Cu" signal "GND7")
		(2 "B.Cu" signal "BOTTOM")
		(9 "F.Adhes" user "F.Adhesive")
		(11 "B.Adhes" user "B.Adhesive")
		(13 "F.Paste" user "Package Geometry/Pastemask Top")
		(15 "B.Paste" user "Package Geometry/Pastemask Bottom")
		(5 "F.SilkS" user "Ref Des/Silkscreen Top")
		(7 "B.SilkS" user "Ref Des/Silkscreen Bottom")
		(1 "F.Mask" user "Board Geometry/Soldermask Top")
		(3 "B.Mask" user "Board Geometry/Soldermask Bottom")
		(17 "Dwgs.User" user "User.Drawings")
		(19 "Cmts.User" user "User.Comments")
		(21 "Eco1.User" user "User.Eco1")
		(23 "Eco2.User" user "User.Eco2")
		(25 "Edge.Cuts" user "Board Geometry/Outline")
		(27 "Margin" user)
		(31 "F.CrtYd" user "Package Geometry/Place Bound Top")
		(29 "B.CrtYd" user "Package Geometry/Place Bound Bottom")
		(35 "F.Fab" user "Ref Des/Assembly Top")
		(33 "B.Fab" user "Ref Des/Assembly Bottom")
	)
	(footprint ""
		(layer "F.Cu")
		(at 210.74888 -42.382948)
		(property "Reference" "R3529"
			(at 0 0 0)
			(layer "F.SilkS")
			(hide yes)
			(effects
				(font
					(size 1.27 1.27)
				)
			)
		)
		(property "Value" ""
			(at 0 0 0)
			(layer "F.Fab")
			(effects
				(font
					(size 1.27 1.27)
				)
			)
		)
		(duplicate_pad_numbers_are_jumpers no)
		(fp_line
			(start -0.7874 -0.4064)
			(end 0.7874 -0.4064)
			(stroke
				(width 0.1524)
				(type default)
			)
			(layer "F.SilkS")
		)
		(fp_line
			(start -0.7874 0.4064)
			(end -0.7874 -0.4064)
			(stroke
				(width 0.1524)
				(type default)
			)
			(layer "F.SilkS")
		)
		(fp_line
			(start 0.7874 -0.4064)
			(end 0.7874 0.4064)
			(stroke
				(width 0.1524)
				(type default)
			)
			(layer "F.SilkS")
		)
		(fp_line
			(start 0.7874 0.4064)
			(end -0.7874 0.4064)
			(stroke
				(width 0.1524)
				(type default)
			)
			(layer "F.SilkS")
		)
		(fp_line
			(start -0.67945 -0.305054)
			(end -0.12065 -0.305054)
			(stroke
				(width 0.1)
				(type default)
			)
			(layer "F.Fab")
		)
		(fp_line
			(start -0.67945 0.3048)
			(end -0.67945 -0.305054)
			(stroke
				(width 0.1)
				(type default)
			)
			(layer "F.Fab")
		)
		(fp_line
			(start -0.12065 -0.305054)
			(end -0.12065 -0.2794)
			(stroke
				(width 0.1)
				(type default)
			)
			(layer "F.Fab")
		)
		(fp_line
			(start -0.12065 -0.2794)
			(end 0.12065 -0.2794)
			(stroke
				(width 0.1)
				(type default)
			)
			(layer "F.Fab")
		)
		(fp_line
			(start -0.12065 0.2794)
			(end -0.12065 0.3048)
			(stroke
				(width 0.1)
				(type default)
			)
			(layer "F.Fab")
		)
		(fp_line
			(start -0.12065 0.3048)
			(end -0.67945 0.3048)
			(stroke
				(width 0.1)
				(type default)
			)
			(layer "F.Fab")
		)
		(fp_line
			(start 0.120396 0.2794)
			(end -0.12065 0.2794)
			(stroke
				(width 0.1)
				(type default)
			)
			(layer "F.Fab")
		)
		(fp_line
			(start 0.120396 0.3048)
			(end 0.120396 0.2794)
			(stroke
				(width 0.1)
				(type default)
			)
			(layer "F.Fab")
		)
		(fp_line
			(start 0.12065 -0.3048)
			(end 0.67945 -0.3048)
			(stroke
				(width 0.1)
				(type default)
			)
			(layer "F.Fab")
		)
		(fp_line
			(start 0.12065 -0.2794)
			(end 0.12065 -0.3048)
			(stroke
				(width 0.1)
				(type default)
			)
			(layer "F.Fab")
		)
		(fp_line
			(start 0.67945 -0.3048)
			(end 0.67945 0.3048)
			(stroke
				(width 0.1)
				(type default)
			)
			(layer "F.Fab")
		)
		(fp_line
			(start 0.67945 0.3048)
			(end 0.120396 0.3048)
			(stroke
				(width 0.1)
				(type default)
			)
			(layer "F.Fab")
		)
		(pad "1" smd circle
			(at -0.40005 0)
			(size 0 0)
			(layers "F.Cu" "F.Mask" "F.Paste")
			(net "P3V3_AUX")
		)
		(pad "2" smd circle
			(at 0.40005 0)
			(size 0 0)
			(layers "F.Cu" "F.Mask" "F.Paste")
			(net "SMB_PCIE_E1S_ISO_EN_R")
		)
	)
	(footprint ""
		(layer "F.Cu")
		(at 517.258808 -153.2128 -90)
		(property "Reference" "X2"
			(at -1.37668 2.83083 90)
			(unlocked yes)
			(layer "F.SilkS")
			(effects
				(font
					(size 0.7874 0.5842)
					(thickness 0.1524)
				)
				(justify left)
			)
		)
		(property "Value" ""
			(at 0 0 270)
			(layer "F.Fab")
			(effects
				(font
					(size 1.27 1.27)
				)
			)
		)
		(property "Device Type" "TP_TDR_4P_FTS_MPKT4_H025P0200_I"
			(at 1.30175 1.27 0)
			(unlocked yes)
			(layer "F.Fab")
			(hide yes)
			(effects
				(font
					(size 0.635 0.4064)
					(thickness 0.1524)
				)
			)
		)
		(property "User Part Number" "TP15"
			(at 1.30175 1.27 0)
			(unlocked yes)
			(layer "Cmts.User")
			(hide yes)
			(effects
				(font
					(size 0.635 0.4064)
					(thickness 0.1524)
				)
			)
		)
		(duplicate_pad_numbers_are_jumpers no)
		(fp_line
			(start 0 3.81)
			(end 2.54 3.81)
			(stroke
				(width 0.1524)
				(type default)
			)
			(layer "F.SilkS")
		)
		(fp_line
			(start 2.54 3.81)
			(end 2.54 3.6703)
			(stroke
				(width 0.1524)
				(type default)
			)
			(layer "F.SilkS")
		)
		(fp_line
			(start 0 3.175)
			(end 0 3.81)
			(stroke
				(width 0.1524)
				(type default)
			)
			(layer "F.SilkS")
		)
		(fp_line
			(start 2.54 1.4097)
			(end 2.54 1.1303)
			(stroke
				(width 0.1524)
				(type default)
			)
			(layer "F.SilkS")
		)
		(fp_line
			(start 0 0.635)
			(end 0 1.905)
			(stroke
				(width 0.1524)
				(type default)
			)
			(layer "F.SilkS")
		)
		(fp_line
			(start 2.54 -1.1303)
			(end 2.54 -1.27)
			(stroke
				(width 0.1524)
				(type default)
			)
			(layer "F.SilkS")
		)
		(fp_line
			(start 0 -1.27)
			(end 0 -0.635)
			(stroke
				(width 0.1524)
				(type default)
			)
			(layer "F.SilkS")
		)
		(fp_line
			(start 2.54 -1.27)
			(end 0 -1.27)
			(stroke
				(width 0.1524)
				(type default)
			)
			(layer "F.SilkS")
		)
		(fp_poly
			(pts
				(xy -1.224026 0.0635) (xy -2.748026 0.8255) (xy -2.748026 -0.6985)
			)
			(stroke
				(width 0)
				(type default)
			)
			(fill yes)
			(layer "F.SilkS")
		)
		(fp_line
			(start 0 3.81)
			(end 2.54 3.81)
			(stroke
				(width 0.1)
				(type default)
			)
			(layer "F.Fab")
		)
		(fp_line
			(start 2.54 3.81)
			(end 2.54 -1.27)
			(stroke
				(width 0.1)
				(type default)
			)
			(layer "F.Fab")
		)
		(fp_line
			(start 0 -1.27)
			(end 0 3.81)
			(stroke
				(width 0.1)
				(type default)
			)
			(layer "F.Fab")
		)
		(fp_line
			(start 2.54 -1.27)
			(end 0 -1.27)
			(stroke
				(width 0.1)
				(type default)
			)
			(layer "F.Fab")
		)
		(fp_poly
			(pts
				(xy -0.761746 0) (xy -2.285746 -0.762) (xy -2.285746 0.762)
			)
			(stroke
				(width 0)
				(type default)
			)
			(fill yes)
			(layer "F.Fab")
		)
		(pad "1" thru_hole circle
			(at 0 0 270)
			(size 1.0033 1.0033)
			(drill 0.249936)
			(layers "*.Cu" "*.Mask")
			(remove_unused_layers no)
			(net "TDR_DIFF_85_IN1_DP")
			(clearance 0.10795)
			(thermal_gap 0.10795)
			(padstack
				(mode front_inner_back)
				(layer "Inner"
					(shape circle)
					(size 0.8001 0.8001)
					(clearance 0.1524)
				)
				(layer "B.Cu"
					(shape circle)
					(size 1.0033 1.0033)
					(clearance 0.10795)
				)
			)
		)
		(pad "2" thru_hole circle
			(at 2.54 0 270)
			(size 1.9939 1.9939)
			(drill 0.249936)
			(layers "*.Cu" "*.Mask")
			(remove_unused_layers no)
			(net "T1_GND")
			(clearance 0.10795)
			(thermal_gap 0.10795)
			(padstack
				(mode front_inner_back)
				(layer "Inner"
					(shape circle)
					(size 0.8001 0.8001)
					(clearance 0.1524)
				)
				(layer "B.Cu"
					(shape circle)
					(size 1.9939 1.9939)
					(clearance 0.10795)
				)
			)
		)
		(pad "3" thru_hole circle
			(at 2.54 2.54 270)
			(size 1.9939 1.9939)
			(drill 0.249936)
			(layers "*.Cu" "*.Mask")
			(remove_unused_layers no)
			(net "T1_GND")
			(clearance 0.10795)
			(thermal_gap 0.10795)
			(padstack
				(mode front_inner_back)
				(layer "Inner"
					(shape circle)
					(size 0.8001 0.8001)
					(clearance 0.1524)
				)
				(layer "B.Cu"
					(shape circle)
					(size 1.9939 1.9939)
					(clearance 0.10795)
				)
			)
		)
		(pad "4" thru_hole circle
			(at 0 2.54 270)
			(size 1.0033 1.0033)
			(drill 0.249936)
			(layers "*.Cu" "*.Mask")
			(remove_unused_layers no)
			(net "TDR_DIFF_85_IN1_DN")
			(clearance 0.10795)
			(thermal_gap 0.10795)
			(padstack
				(mode front_inner_back)
				(layer "Inner"
					(shape circle)
					(size 0.8001 0.8001)
					(clearance 0.1524)
				)
				(layer "B.Cu"
					(shape circle)
					(size 1.0033 1.0033)
					(clearance 0.10795)
				)
			)
		)
	)
	(footprint ""
		(layer "F.Cu")
		(at 165.53815 -418.514276 -90)
		(property "Reference" "R2672"
			(at 0 0 270)
			(layer "F.SilkS")
			(hide yes)
			(effects
				(font
					(size 1.27 1.27)
				)
			)
		)
		(property "Value" ""
			(at 0 0 270)
			(layer "F.Fab")
			(effects
				(font
					(size 1.27 1.27)
				)
			)
		)
		(duplicate_pad_numbers_are_jumpers no)
		(fp_line
			(start -0.7874 0.4064)
			(end -0.7874 -0.4064)
			(stroke
				(width 0.1524)
				(type default)
			)
			(layer "F.SilkS")
		)
		(fp_line
			(start 0.7874 0.4064)
			(end -0.7874 0.4064)
			(stroke
				(width 0.1524)
				(type default)
			)
			(layer "F.SilkS")
		)
		(fp_line
			(start -0.7874 -0.4064)
			(end 0.7874 -0.4064)
			(stroke
				(width 0.1524)
				(type default)
			)
			(layer "F.SilkS")
		)
		(fp_line
			(start 0.7874 -0.4064)
			(end 0.7874 0.4064)
			(stroke
				(width 0.1524)
				(type default)
			)
			(layer "F.SilkS")
		)
		(fp_line
			(start -0.67945 0.3048)
			(end -0.67945 -0.305054)
			(stroke
				(width 0.1)
				(type default)
			)
			(layer "F.Fab")
		)
		(fp_line
			(start -0.12065 0.3048)
			(end -0.67945 0.3048)
			(stroke
				(width 0.1)
				(type default)
			)
			(layer "F.Fab")
		)
		(fp_line
			(start 0.120396 0.3048)
			(end 0.120396 0.2794)
			(stroke
				(width 0.1)
				(type default)
			)
			(layer "F.Fab")
		)
		(fp_line
			(start 0.67945 0.3048)
			(end 0.120396 0.3048)
			(stroke
				(width 0.1)
				(type default)
			)
			(layer "F.Fab")
		)
		(fp_line
			(start -0.12065 0.2794)
			(end -0.12065 0.3048)
			(stroke
				(width 0.1)
				(type default)
			)
			(layer "F.Fab")
		)
		(fp_line
			(start 0.120396 0.2794)
			(end -0.12065 0.2794)
			(stroke
				(width 0.1)
				(type default)
			)
			(layer "F.Fab")
		)
		(fp_line
			(start -0.12065 -0.2794)
			(end 0.12065 -0.2794)
			(stroke
				(width 0.1)
				(type default)
			)
			(layer "F.Fab")
		)
		(fp_line
			(start 0.12065 -0.2794)
			(end 0.12065 -0.3048)
			(stroke
				(width 0.1)
				(type default)
			)
			(layer "F.Fab")
		)
		(fp_line
			(start 0.12065 -0.3048)
			(end 0.67945 -0.3048)
			(stroke
				(width 0.1)
				(type default)
			)
			(layer "F.Fab")
		)
		(fp_line
			(start 0.67945 -0.3048)
			(end 0.67945 0.3048)
			(stroke
				(width 0.1)
				(type default)
			)
			(layer "F.Fab")
		)
		(fp_line
			(start -0.67945 -0.305054)
			(end -0.12065 -0.305054)
			(stroke
				(width 0.1)
				(type default)
			)
			(layer "F.Fab")
		)
		(fp_line
			(start -0.12065 -0.305054)
			(end -0.12065 -0.2794)
			(stroke
				(width 0.1)
				(type default)
			)
			(layer "F.Fab")
		)
		(pad "1" smd circle
			(at -0.40005 0 270)
			(size 0 0)
			(layers "F.Cu" "F.Mask" "F.Paste")
			(net "SMB_BMC_SWB_BUF_R_SDA")
		)
		(pad "2" smd circle
			(at 0.40005 0 270)
			(size 0 0)
			(layers "F.Cu" "F.Mask" "F.Paste")
			(net "SMB_BMC_SWB_BUF_SDA")
		)
	)
	(footprint ""
		(layer "F.Cu")
		(at 360.383582 -385.17449)
		(property "Reference" "R4167"
			(at 0 0 0)
			(layer "F.SilkS")
			(hide yes)
			(effects
				(font
					(size 1.27 1.27)
				)
			)
		)
		(property "Value" ""
			(at 0 0 0)
			(layer "F.Fab")
			(effects
				(font
					(size 1.27 1.27)
				)
			)
		)
		(duplicate_pad_numbers_are_jumpers no)
		(fp_line
			(start -0.7874 -0.4064)
			(end 0.7874 -0.4064)
			(stroke
				(width 0.1524)
				(type default)
			)
			(layer "F.SilkS")
		)
		(fp_line
			(start -0.7874 0.4064)
			(end -0.7874 -0.4064)
			(stroke
				(width 0.1524)
				(type default)
			)
			(layer "F.SilkS")
		)
		(fp_line
			(start 0.7874 -0.4064)
			(end 0.7874 0.4064)
			(stroke
				(width 0.1524)
				(type default)
			)
			(layer "F.SilkS")
		)
		(fp_line
			(start 0.7874 0.4064)
			(end -0.7874 0.4064)
			(stroke
				(width 0.1524)
				(type default)
			)
			(layer "F.SilkS")
		)
		(fp_line
			(start -0.67945 -0.305054)
			(end -0.12065 -0.305054)
			(stroke
				(width 0.1)
				(type default)
			)
			(layer "F.Fab")
		)
		(fp_line
			(start -0.67945 0.3048)
			(end -0.67945 -0.305054)
			(stroke
				(width 0.1)
				(type default)
			)
			(layer "F.Fab")
		)
		(fp_line
			(start -0.12065 -0.305054)
			(end -0.12065 -0.2794)
			(stroke
				(width 0.1)
				(type default)
			)
			(layer "F.Fab")
		)
		(fp_line
			(start -0.12065 -0.2794)
			(end 0.12065 -0.2794)
			(stroke
				(width 0.1)
				(type default)
			)
			(layer "F.Fab")
		)
		(fp_line
			(start -0.12065 0.2794)
			(end -0.12065 0.3048)
			(stroke
				(width 0.1)
				(type default)
			)
			(layer "F.Fab")
		)
		(fp_line
			(start -0.12065 0.3048)
			(end -0.67945 0.3048)
			(stroke
				(width 0.1)
				(type default)
			)
			(layer "F.Fab")
		)
		(fp_line
			(start 0.120396 0.2794)
			(end -0.12065 0.2794)
			(stroke
				(width 0.1)
				(type default)
			)
			(layer "F.Fab")
		)
		(fp_line
			(start 0.120396 0.3048)
			(end 0.120396 0.2794)
			(stroke
				(width 0.1)
				(type default)
			)
			(layer "F.Fab")
		)
		(fp_line
			(start 0.12065 -0.3048)
			(end 0.67945 -0.3048)
			(stroke
				(width 0.1)
				(type default)
			)
			(layer "F.Fab")
		)
		(fp_line
			(start 0.12065 -0.2794)
			(end 0.12065 -0.3048)
			(stroke
				(width 0.1)
				(type default)
			)
			(layer "F.Fab")
		)
		(fp_line
			(start 0.67945 -0.3048)
			(end 0.67945 0.3048)
			(stroke
				(width 0.1)
				(type default)
			)
			(layer "F.Fab")
		)
		(fp_line
			(start 0.67945 0.3048)
			(end 0.120396 0.3048)
			(stroke
				(width 0.1)
				(type default)
			)
			(layer "F.Fab")
		)
		(pad "1" smd circle
			(at -0.40005 0)
			(size 0 0)
			(layers "F.Cu" "F.Mask" "F.Paste")
			(net "P3V3_AUX")
		)
		(pad "2" smd circle
			(at 0.40005 0)
			(size 0 0)
			(layers "F.Cu" "F.Mask" "F.Paste")
			(net "GPU_3V3IO_RSVD1_ISO")
		)
	)
	(footprint ""
		(layer "F.Cu")
		(at 119.508016 -238.162592 90)
		(property "Reference" "C440"
			(at 0 0 90)
			(layer "F.SilkS")
			(hide yes)
			(effects
				(font
					(size 1.27 1.27)
				)
			)
		)
		(property "Value" ""
			(at 0 0 90)
			(layer "F.Fab")
			(effects
				(font
					(size 1.27 1.27)
				)
			)
		)
		(duplicate_pad_numbers_are_jumpers no)
		(fp_line
			(start 0.7874 -0.4064)
			(end 0.7874 0.4064)
			(stroke
				(width 0.1524)
				(type default)
			)
			(layer "F.SilkS")
		)
		(fp_line
			(start -0.7874 -0.4064)
			(end 0.7874 -0.4064)
			(stroke
				(width 0.1524)
				(type default)
			)
			(layer "F.SilkS")
		)
		(fp_line
			(start 0.7874 0.4064)
			(end -0.7874 0.4064)
			(stroke
				(width 0.1524)
				(type default)
			)
			(layer "F.SilkS")
		)
		(fp_line
			(start -0.7874 0.4064)
			(end -0.7874 -0.4064)
			(stroke
				(width 0.1524)
				(type default)
			)
			(layer "F.SilkS")
		)
		(fp_line
			(start -0.12065 -0.305054)
			(end -0.12065 -0.2794)
			(stroke
				(width 0.1)
				(type default)
			)
			(layer "F.Fab")
		)
		(fp_line
			(start -0.67945 -0.305054)
			(end -0.12065 -0.305054)
			(stroke
				(width 0.1)
				(type default)
			)
			(layer "F.Fab")
		)
		(fp_line
			(start 0.67945 -0.3048)
			(end 0.67945 0.3048)
			(stroke
				(width 0.1)
				(type default)
			)
			(layer "F.Fab")
		)
		(fp_line
			(start 0.12065 -0.3048)
			(end 0.67945 -0.3048)
			(stroke
				(width 0.1)
				(type default)
			)
			(layer "F.Fab")
		)
		(fp_line
			(start 0.12065 -0.2794)
			(end 0.12065 -0.3048)
			(stroke
				(width 0.1)
				(type default)
			)
			(layer "F.Fab")
		)
		(fp_line
			(start -0.12065 -0.2794)
			(end 0.12065 -0.2794)
			(stroke
				(width 0.1)
				(type default)
			)
			(layer "F.Fab")
		)
		(fp_line
			(start 0.120396 0.2794)
			(end -0.12065 0.2794)
			(stroke
				(width 0.1)
				(type default)
			)
			(layer "F.Fab")
		)
		(fp_line
			(start -0.12065 0.2794)
			(end -0.12065 0.3048)
			(stroke
				(width 0.1)
				(type default)
			)
			(layer "F.Fab")
		)
		(fp_line
			(start 0.67945 0.3048)
			(end 0.120396 0.3048)
			(stroke
				(width 0.1)
				(type default)
			)
			(layer "F.Fab")
		)
		(fp_line
			(start 0.120396 0.3048)
			(end 0.120396 0.2794)
			(stroke
				(width 0.1)
				(type default)
			)
			(layer "F.Fab")
		)
		(fp_line
			(start -0.12065 0.3048)
			(end -0.67945 0.3048)
			(stroke
				(width 0.1)
				(type default)
			)
			(layer "F.Fab")
		)
		(fp_line
			(start -0.67945 0.3048)
			(end -0.67945 -0.305054)
			(stroke
				(width 0.1)
				(type default)
			)
			(layer "F.Fab")
		)
		(pad "1" smd circle
			(at -0.40005 0 90)
			(size 0 0)
			(layers "F.Cu" "F.Mask" "F.Paste")
			(net "PVCCINFAON_CPU1")
		)
		(pad "2" smd circle
			(at 0.40005 0 90)
			(size 0 0)
			(layers "F.Cu" "F.Mask" "F.Paste")
			(net "GND")
		)
	)
)
